(kicad_pcb
	(version 20260206)
	(generator "pcbnew")
	(generator_version "10.0")
	(general
		(thickness 1.6)
		(legacy_teardrops no)
	)
	(paper "A4")
	(title_block
		(title "01162023_DA0F0TEBIF0_F0T_Expander_BD_F_brd_V02_OCP.brd")
		(comment 1 "Grand Teton / footprints 4565-4568 of 9728")
	)
	(layers
		(0 "F.Cu" signal "TOP")
		(4 "In1.Cu" signal "GND")
		(6 "In2.Cu" signal "VCC")
		(8 "In3.Cu" signal "VCC1")
		(10 "In4.Cu" signal "GND1")
		(12 "In5.Cu" signal "IN1")
		(14 "In6.Cu" signal "GND2")
		(16 "In7.Cu" signal "IN2")
		(18 "In8.Cu" signal "GND3")
		(20 "In9.Cu" signal "IN3")
		(22 "In10.Cu" signal "GND4")
		(24 "In11.Cu" signal "IN4")
		(26 "In12.Cu" signal "GND5")
		(28 "In13.Cu" signal "IN5")
		(30 "In14.Cu" signal "GND6")
		(32 "In15.Cu" signal "IN6")
		(34 "In16.Cu" signal "GND7")
		(2 "B.Cu" signal "BOTTOM")
		(9 "F.Adhes" user "F.Adhesive")
		(11 "B.Adhes" user "B.Adhesive")
		(13 "F.Paste" user "Package Geometry/Pastemask Top")
		(15 "B.Paste" user "Package Geometry/Pastemask Bottom")
		(5 "F.SilkS" user "Ref Des/Silkscreen Top")
		(7 "B.SilkS" user "Ref Des/Silkscreen Bottom")
		(1 "F.Mask" user "Board Geometry/Soldermask Top")
		(3 "B.Mask" user "Board Geometry/Soldermask Bottom")
		(17 "Dwgs.User" user "User.Drawings")
		(19 "Cmts.User" user "User.Comments")
		(21 "Eco1.User" user "User.Eco1")
		(23 "Eco2.User" user "User.Eco2")
		(25 "Edge.Cuts" user "Board Geometry/Outline")
		(27 "Margin" user)
		(31 "F.CrtYd" user "Package Geometry/Place Bound Top")
		(29 "B.CrtYd" user "Package Geometry/Place Bound Bottom")
		(35 "F.Fab" user "Ref Des/Assembly Top")
		(33 "B.Fab" user "Ref Des/Assembly Bottom")
	)
	(footprint ""
		(layer "F.Cu")
		(at 79.683356 -238.6076)
		(property "Reference" "J73"
			(at -1.4224 -4.562348 0)
			(unlocked yes)
			(layer "F.SilkS")
			(effects
				(font
					(size 0.7874 0.5842)
					(thickness 0.1524)
				)
				(justify left)
			)
		)
		(property "Value" ""
			(at 0 0 0)
			(layer "F.Fab")
			(effects
				(font
					(size 1.27 1.27)
				)
			)
		)
		(duplicate_pad_numbers_are_jumpers no)
		(fp_line
			(start -1.27 -3.81)
			(end 1.27 -3.81)
			(stroke
				(width 0.1524)
				(type default)
			)
			(layer "F.SilkS")
		)
		(fp_line
			(start -1.27 -0.7747)
			(end -1.27 -3.81)
			(stroke
				(width 0.1524)
				(type default)
			)
			(layer "F.SilkS")
		)
		(fp_line
			(start -1.27 3.81)
			(end -1.27 0.7747)
			(stroke
				(width 0.1524)
				(type default)
			)
			(layer "F.SilkS")
		)
		(fp_line
			(start 1.27 -3.81)
			(end 1.27 -3.3147)
			(stroke
				(width 0.1524)
				(type default)
			)
			(layer "F.SilkS")
		)
		(fp_line
			(start 1.27 -1.7653)
			(end 1.27 1.7653)
			(stroke
				(width 0.1524)
				(type default)
			)
			(layer "F.SilkS")
		)
		(fp_line
			(start 1.27 3.3147)
			(end 1.27 3.81)
			(stroke
				(width 0.1524)
				(type default)
			)
			(layer "F.SilkS")
		)
		(fp_line
			(start 1.27 3.81)
			(end -1.27 3.81)
			(stroke
				(width 0.1524)
				(type default)
			)
			(layer "F.SilkS")
		)
		(fp_poly
			(pts
				(xy 4.3942 -3.048) (xy 4.3942 -2.032) (xy 3.3782 -2.54)
			)
			(stroke
				(width 0)
				(type default)
			)
			(fill yes)
			(layer "F.SilkS")
		)
		(fp_line
			(start -1.27 -3.81)
			(end -1.27 3.81)
			(stroke
				(width 0.1)
				(type default)
			)
			(layer "F.Fab")
		)
		(fp_line
			(start -1.27 3.81)
			(end 1.27 3.81)
			(stroke
				(width 0.1)
				(type default)
			)
			(layer "F.Fab")
		)
		(fp_line
			(start 1.27 -3.81)
			(end -1.27 -3.81)
			(stroke
				(width 0.1)
				(type default)
			)
			(layer "F.Fab")
		)
		(fp_line
			(start 1.27 3.81)
			(end 1.27 -3.81)
			(stroke
				(width 0.1)
				(type default)
			)
			(layer "F.Fab")
		)
		(fp_poly
			(pts
				(xy 4.3942 -3.048) (xy 4.3942 -2.032) (xy 3.3782 -2.54)
			)
			(stroke
				(width 0)
				(type default)
			)
			(fill yes)
			(layer "F.Fab")
		)
		(fp_text user "3"
			(at 3.921252 2.54 90)
			(unlocked yes)
			(layer "F.SilkS")
			(effects
				(font
					(size 0.7874 0.5842)
					(thickness 0.1524)
				)
			)
		)
		(fp_text user "3"
			(at 3.921252 2.54 90)
			(unlocked yes)
			(layer "F.Fab")
			(effects
				(font
					(size 0.7874 0.5842)
					(thickness 0.1524)
				)
			)
		)
		(pad "1" smd rect
			(at 1.459992 -2.54 90)
			(size 1.27 3.429)
			(layers "F.Cu" "F.Mask" "F.Paste")
			(net "GND")
		)
		(pad "2" smd rect
			(at -1.459992 0 90)
			(size 1.27 3.429)
			(layers "F.Cu" "F.Mask" "F.Paste")
			(net "UART_PEX0_CLI_BUF_R1_TX")
		)
		(pad "3" smd rect
			(at 1.459992 2.54 90)
			(size 1.27 3.429)
			(layers "F.Cu" "F.Mask" "F.Paste")
			(net "UART_PEX0_CLI_R1_RX")
		)
	)
	(footprint ""
		(layer "F.Cu")
		(at 399.161254 -169.23385 180)
		(property "Reference" "C948"
			(at 0 0 180)
			(layer "F.SilkS")
			(hide yes)
			(effects
				(font
					(size 1.27 1.27)
				)
			)
		)
		(property "Value" ""
			(at 0 0 180)
			(layer "F.Fab")
			(effects
				(font
					(size 1.27 1.27)
				)
			)
		)
		(duplicate_pad_numbers_are_jumpers no)
		(fp_line
			(start 0.7874 0.4064)
			(end -0.7874 0.4064)
			(stroke
				(width 0.1524)
				(type default)
			)
			(layer "F.SilkS")
		)
		(fp_line
			(start 0.7874 -0.4064)
			(end 0.7874 0.4064)
			(stroke
				(width 0.1524)
				(type default)
			)
			(layer "F.SilkS")
		)
		(fp_line
			(start -0.7874 0.4064)
			(end -0.7874 -0.4064)
			(stroke
				(width 0.1524)
				(type default)
			)
			(layer "F.SilkS")
		)
		(fp_line
			(start -0.7874 -0.4064)
			(end 0.7874 -0.4064)
			(stroke
				(width 0.1524)
				(type default)
			)
			(layer "F.SilkS")
		)
		(fp_line
			(start 0.67945 0.3048)
			(end 0.120396 0.3048)
			(stroke
				(width 0.1)
				(type default)
			)
			(layer "F.Fab")
		)
		(fp_line
			(start 0.67945 -0.3048)
			(end 0.67945 0.3048)
			(stroke
				(width 0.1)
				(type default)
			)
			(layer "F.Fab")
		)
		(fp_line
			(start 0.12065 -0.2794)
			(end 0.12065 -0.3048)
			(stroke
				(width 0.1)
				(type default)
			)
			(layer "F.Fab")
		)
		(fp_line
			(start 0.12065 -0.3048)
			(end 0.67945 -0.3048)
			(stroke
				(width 0.1)
				(type default)
			)
			(layer "F.Fab")
		)
		(fp_line
			(start 0.120396 0.3048)
			(end 0.120396 0.2794)
			(stroke
				(width 0.1)
				(type default)
			)
			(layer "F.Fab")
		)
		(fp_line
			(start 0.120396 0.2794)
			(end -0.12065 0.2794)
			(stroke
				(width 0.1)
				(type default)
			)
			(layer "F.Fab")
		)
		(fp_line
			(start -0.12065 0.3048)
			(end -0.67945 0.3048)
			(stroke
				(width 0.1)
				(type default)
			)
			(layer "F.Fab")
		)
		(fp_line
			(start -0.12065 0.2794)
			(end -0.12065 0.3048)
			(stroke
				(width 0.1)
				(type default)
			)
			(layer "F.Fab")
		)
		(fp_line
			(start -0.12065 -0.2794)
			(end 0.12065 -0.2794)
			(stroke
				(width 0.1)
				(type default)
			)
			(layer "F.Fab")
		)
		(fp_line
			(start -0.12065 -0.305054)
			(end -0.12065 -0.2794)
			(stroke
				(width 0.1)
				(type default)
			)
			(layer "F.Fab")
		)
		(fp_line
			(start -0.67945 0.3048)
			(end -0.67945 -0.305054)
			(stroke
				(width 0.1)
				(type default)
			)
			(layer "F.Fab")
		)
		(fp_line
			(start -0.67945 -0.305054)
			(end -0.12065 -0.305054)
			(stroke
				(width 0.1)
				(type default)
			)
			(layer "F.Fab")
		)
		(pad "1" smd circle
			(at -0.40005 0 180)
			(size 0 0)
			(layers "F.Cu" "F.Mask" "F.Paste")
			(net "P3V3_AUX")
		)
		(pad "2" smd circle
			(at 0.40005 0 180)
			(size 0 0)
			(layers "F.Cu" "F.Mask" "F.Paste")
			(net "GND")
		)
	)
	(footprint ""
		(layer "F.Cu")
		(at 261.84987 -270.89989)
		(property "Reference" "H87"
			(at -6.03758 -7.57301 0)
			(unlocked yes)
			(layer "F.SilkS")
			(effects
				(font
					(size 0.7874 0.5842)
					(thickness 0.1524)
				)
				(justify left)
			)
		)
		(property "Value" ""
			(at 0 0 0)
			(layer "F.Fab")
			(effects
				(font
					(size 1.27 1.27)
				)
			)
		)
		(duplicate_pad_numbers_are_jumpers no)
		(fp_arc
			(start 7.956804 -0.829056)
			(mid 7.989153 -0.415088)
			(end 7.999984 0)
			(stroke
				(width 0.1524)
				(type default)
			)
			(layer "F.SilkS")
		)
		(fp_arc
			(start 7.999984 0)
			(mid -7.434041 2.956443)
			(end 5.815076 -5.49402)
			(stroke
				(width 0.1524)
				(type default)
			)
			(layer "F.SilkS")
		)
		(fp_arc
			(start -7.978902 0.572262)
			(mid -6.692786 -4.381853)
			(end -2.666746 -7.542276)
			(stroke
				(width 0.1524)
				(type default)
			)
			(layer "B.SilkS")
		)
		(fp_arc
			(start 1.305052 -7.892796)
			(mid 3.864626 -7.004714)
			(end 5.980938 -5.313172)
			(stroke
				(width 0.1524)
				(type default)
			)
			(layer "B.SilkS")
		)
		(fp_arc
			(start 7.90702 -1.216914)
			(mid 7.976737 -0.610232)
			(end 7.999984 0)
			(stroke
				(width 0.1524)
				(type default)
			)
			(layer "B.SilkS")
		)
		(fp_arc
			(start 7.999984 0)
			(mid 2.208063 7.688973)
			(end -6.780784 4.244086)
			(stroke
				(width 0.1524)
				(type default)
			)
			(layer "B.SilkS")
		)
		(fp_circle
			(center 0 0)
			(end 7.999984 0)
			(stroke
				(width 0.1)
				(type default)
			)
			(fill no)
			(layer "B.Fab")
		)
		(fp_circle
			(center 0 0)
			(end 7.999984 0)
			(stroke
				(width 0.1)
				(type default)
			)
			(fill no)
			(layer "F.Fab")
		)
		(pad "" np_thru_hole circle
			(at 0 0)
			(size 4.5212 4.5212)
			(drill 4.5212)
			(layers "*.Cu" "*.Mask")
			(clearance 0.381)
			(thermal_gap 0.381)
		)
		(pad "2" thru_hole circle
			(at 3.6322 0)
			(size 0.762 0.762)
			(drill 0.5588)
			(layers "*.Cu" "*.Mask")
			(remove_unused_layers no)
			(net "GND")
			(clearance 0.1524)
			(thermal_gap 0.1524)
		)
		(pad "3" thru_hole circle
			(at 2.568448 -2.568448)
			(size 0.762 0.762)
			(drill 0.5588)
			(layers "*.Cu" "*.Mask")
			(remove_unused_layers no)
			(net "GND")
			(clearance 0.1524)
			(thermal_gap 0.1524)
		)
		(pad "4" thru_hole circle
			(at 0 -3.6322)
			(size 0.762 0.762)
			(drill 0.5588)
			(layers "*.Cu" "*.Mask")
			(remove_unused_layers no)
			(net "GND")
			(clearance 0.1524)
			(thermal_gap 0.1524)
		)
		(pad "5" thru_hole circle
			(at -2.568448 -2.568448)
			(size 0.762 0.762)
			(drill 0.5588)
			(layers "*.Cu" "*.Mask")
			(remove_unused_layers no)
			(net "GND")
			(clearance 0.1524)
			(thermal_gap 0.1524)
		)
		(pad "6" thru_hole circle
			(at -3.6322 0)
			(size 0.762 0.762)
			(drill 0.5588)
			(layers "*.Cu" "*.Mask")
			(remove_unused_layers no)
			(net "GND")
			(clearance 0.1524)
			(thermal_gap 0.1524)
		)
		(pad "7" thru_hole circle
			(at -2.568448 2.568448)
			(size 0.762 0.762)
			(drill 0.5588)
			(layers "*.Cu" "*.Mask")
			(remove_unused_layers no)
			(net "GND")
			(clearance 0.1524)
			(thermal_gap 0.1524)
		)
		(pad "8" thru_hole circle
			(at 0 3.6322)
			(size 0.762 0.762)
			(drill 0.5588)
			(layers "*.Cu" "*.Mask")
			(remove_unused_layers no)
			(net "GND")
			(clearance 0.1524)
			(thermal_gap 0.1524)
		)
		(pad "9" thru_hole circle
			(at 2.568448 2.568448)
			(size 0.762 0.762)
			(drill 0.5588)
			(layers "*.Cu" "*.Mask")
			(remove_unused_layers no)
			(net "GND")
			(clearance 0.1524)
			(thermal_gap 0.1524)
		)
		(zone
			(layer "F.Cu")
			(hatch none 0.5)
			(connect_pads
				(clearance 0)
			)
			(min_thickness 0.25)
			(keepout
				(tracks not_allowed)
				(vias allowed)
				(pads allowed)
				(copperpour not_allowed)
				(footprints allowed)
			)
			(placement
				(enabled no)
				(sheetname "")
			)
			(fill
				(thermal_gap 0.5)
				(thermal_bridge_width 0.5)
				(island_removal_mode 0)
			)
			(polygon
				(pts
					(arc
						(start 261.84987 -262.899906)
						(mid 253.849886 -270.89989)
						(end 261.84987 -278.899874)
					)
					(arc
						(start 261.84987 -275.64969)
						(mid 257.10007 -270.89989)
						(end 261.84987 -266.15009)
					)
				)
			)
		)
		(zone
			(layer "F.Cu")
			(hatch none 0.5)
			(connect_pads
				(clearance 0)
			)
			(min_thickness 0.25)
			(keepout
				(tracks not_allowed)
				(vias allowed)
				(pads allowed)
				(copperpour not_allowed)
				(footprints allowed)
			)
			(placement
				(enabled no)
				(sheetname "")
			)
			(fill
				(thermal_gap 0.5)
				(thermal_bridge_width 0.5)
				(island_removal_mode 0)
			)
			(polygon
				(pts
					(arc
						(start 261.84987 -262.899906)
						(mid 269.849854 -270.89989)
						(end 261.84987 -278.899874)
					)
					(arc
						(start 261.84987 -275.64969)
						(mid 266.59967 -270.89989)
						(end 261.84987 -266.15009)
					)
				)
			)
		)
		(zone
			(layers "F.Cu" "B.Cu" "In1.Cu" "In2.Cu" "In3.Cu" "In4.Cu" "In5.Cu" "In6.Cu"
				"In7.Cu" "In8.Cu" "In9.Cu" "In10.Cu" "In11.Cu" "In12.Cu" "In13.Cu" "In14.Cu"
				"In15.Cu" "In16.Cu"
			)
			(hatch none 0.5)
			(connect_pads
				(clearance 0)
			)
			(min_thickness 0.25)
			(keepout
				(tracks not_allowed)
				(vias allowed)
				(pads allowed)
				(copperpour not_allowed)
				(footprints allowed)
			)
			(placement
				(enabled no)
				(sheetname "")
			)
			(fill
				(thermal_gap 0.5)
				(thermal_bridge_width 0.5)
				(island_removal_mode 0)
			)
			(polygon
				(pts
					(arc
						(start 264.61593 -270.89989)
						(mid 259.08381 -270.89989)
						(end 264.61593 -270.89989)
					)
				)
			)
		)
		(zone
			(layer "B.Cu")
			(hatch none 0.5)
			(connect_pads
				(clearance 0)
			)
			(min_thickness 0.25)
			(keepout
				(tracks not_allowed)
				(vias allowed)
				(pads allowed)
				(copperpour not_allowed)
				(footprints allowed)
			)
			(placement
				(enabled no)
				(sheetname "")
			)
			(fill
				(thermal_gap 0.5)
				(thermal_bridge_width 0.5)
				(island_removal_mode 0)
			)
			(polygon
				(pts
					(arc
						(start 261.84987 -265.89609)
						(mid 256.84607 -270.89989)
						(end 261.84987 -275.90369)
					)
					(arc
						(start 261.84987 -275.42109)
						(mid 257.32867 -270.89989)
						(end 261.84987 -266.37869)
					)
				)
			)
		)
		(zone
			(layer "B.Cu")
			(hatch none 0.5)
			(connect_pads
				(clearance 0)
			)
			(min_thickness 0.25)
			(keepout
				(tracks not_allowed)
				(vias allowed)
				(pads allowed)
				(copperpour not_allowed)
				(footprints allowed)
			)
			(placement
				(enabled no)
				(sheetname "")
			)
			(fill
				(thermal_gap 0.5)
				(thermal_bridge_width 0.5)
				(island_removal_mode 0)
			)
			(polygon
				(pts
					(arc
						(start 261.84987 -265.89609)
						(mid 266.85367 -270.89989)
						(end 261.84987 -275.90369)
					)
					(arc
						(start 261.84987 -275.42109)
						(mid 266.37107 -270.89989)
						(end 261.84987 -266.37869)
					)
				)
			)
		)
	)
	(footprint ""
		(layer "F.Cu")
		(at 84.709 -26.03373)
		(property "Reference" "R4058"
			(at 0 0 0)
			(layer "F.SilkS")
			(hide yes)
			(effects
				(font
					(size 1.27 1.27)
				)
			)
		)
		(property "Value" ""
			(at 0 0 0)
			(layer "F.Fab")
			(effects
				(font
					(size 1.27 1.27)
				)
			)
		)
		(duplicate_pad_numbers_are_jumpers no)
		(fp_line
			(start -0.7874 -0.4064)
			(end 0.7874 -0.4064)
			(stroke
				(width 0.1524)
				(type default)
			)
			(layer "F.SilkS")
		)
		(fp_line
			(start -0.7874 0.4064)
			(end -0.7874 -0.4064)
			(stroke
				(width 0.1524)
				(type default)
			)
			(layer "F.SilkS")
		)
		(fp_line
			(start 0.7874 -0.4064)
			(end 0.7874 0.4064)
			(stroke
				(width 0.1524)
				(type default)
			)
			(layer "F.SilkS")
		)
		(fp_line
			(start 0.7874 0.4064)
			(end -0.7874 0.4064)
			(stroke
				(width 0.1524)
				(type default)
			)
			(layer "F.SilkS")
		)
		(fp_line
			(start -0.67945 -0.305054)
			(end -0.12065 -0.305054)
			(stroke
				(width 0.1)
				(type default)
			)
			(layer "F.Fab")
		)
		(fp_line
			(start -0.67945 0.3048)
			(end -0.67945 -0.305054)
			(stroke
				(width 0.1)
				(type default)
			)
			(layer "F.Fab")
		)
		(fp_line
			(start -0.12065 -0.305054)
			(end -0.12065 -0.2794)
			(stroke
				(width 0.1)
				(type default)
			)
			(layer "F.Fab")
		)
		(fp_line
			(start -0.12065 -0.2794)
			(end 0.12065 -0.2794)
			(stroke
				(width 0.1)
				(type default)
			)
			(layer "F.Fab")
		)
		(fp_line
			(start -0.12065 0.2794)
			(end -0.12065 0.3048)
			(stroke
				(width 0.1)
				(type default)
			)
			(layer "F.Fab")
		)
		(fp_line
			(start -0.12065 0.3048)
			(end -0.67945 0.3048)
			(stroke
				(width 0.1)
				(type default)
			)
			(layer "F.Fab")
		)
		(fp_line
			(start 0.120396 0.2794)
			(end -0.12065 0.2794)
			(stroke
				(width 0.1)
				(type default)
			)
			(layer "F.Fab")
		)
		(fp_line
			(start 0.120396 0.3048)
			(end 0.120396 0.2794)
			(stroke
				(width 0.1)
				(type default)
			)
			(layer "F.Fab")
		)
		(fp_line
			(start 0.12065 -0.3048)
			(end 0.67945 -0.3048)
			(stroke
				(width 0.1)
				(type default)
			)
			(layer "F.Fab")
		)
		(fp_line
			(start 0.12065 -0.2794)
			(end 0.12065 -0.3048)
			(stroke
				(width 0.1)
				(type default)
			)
			(layer "F.Fab")
		)
		(fp_line
			(start 0.67945 -0.3048)
			(end 0.67945 0.3048)
			(stroke
				(width 0.1)
				(type default)
			)
			(layer "F.Fab")
		)
		(fp_line
			(start 0.67945 0.3048)
			(end 0.120396 0.3048)
			(stroke
				(width 0.1)
				(type default)
			)
			(layer "F.Fab")
		)
		(pad "1" smd circle
			(at -0.40005 0)
			(size 0 0)
			(layers "F.Cu" "F.Mask" "F.Paste")
			(net "P3V3_AUX")
		)
		(pad "2" smd circle
			(at 0.40005 0)
			(size 0 0)
			(layers "F.Cu" "F.Mask" "F.Paste")
			(net "PRSNT_SSD3_R_N")
		)
	)
)
